FILE_TYPE = MULTI_PHYS_TABLE;

PART '74LV4052PW'

{========================================================================================}
:VALUE        | PART_TYPE | MATERIAL | PART_NUMBER    = STANDARD | LIFECYCLE      | PART_NUMBER   | JEDEC_TYPE             | DESCRIPTION                       | MANUFTR | MANUF_PN     | RD_CMPLS_LVL | CMPLS_LVL | FROM_PJ    | CLASS | DIP_SMD | DATA                 | EE_CHECK_LIST | FP_ECN | PSL | CREATOR | STATUS | MSD  | ESD_CDM | ESD_HBM | ESD_MM | PIN_LENGTH_SHORT_PIN | PIN_LENGTH_LONG_PIN | CREATEDAY  ;
{========================================================================================}
 '74LV4052PW' | 'SMLF'    | 'IC'     | 'ALLV4052K19'(!) = ''       | ''               | 'ALLV4052K19' |'TSSOP16_0-65_5X4-4XH'| 'IC OTHERS(16P)74LV4052PW(TSSOP)' | 'PHI'   | '74LV4052PW' | 'EP'         | 'EP'      | 'A5W-JANE' | 'IC'  | ''      | 'PHI_74LV4052PW.pdf' | ''            | ''     | ''  | ''      | ''     | 'NA' | 'NA'    | 'NA'    | 'NA'   | '0 MILS'             | '0 MILS'            | '20190711'
 '74LV4052PW' | 'SMLF'    | 'EMPTY'  | 'ALLV4052K19'(!) = ''       | ''               | 'ALLV4052K19' |'TSSOP16_0-65_5X4-4XH'| 'IC OTHERS(16P)74LV4052PW(TSSOP)' | 'PHI'   | '74LV4052PW' | 'EP'         | 'EP'      | 'A5W-JANE' | 'IC'  | ''      | 'PHI_74LV4052PW.pdf' | ''            | ''     | ''  | ''      | ''     | 'NA' | 'NA'    | 'NA'    | 'NA'   | '0 MILS'             | '0 MILS'            | '20190711'

END_PART

END.

